# S9S_MB_2U (Grand Teton) — schematic netlist excerpt (pin names and nets, part order shuffled) for the footprints in the layout excerpt that follows; sources: Cadence DE-HDL packaged netlist, KiCad conversion of 03242023_DA0F0TMBIJ0_F0T_Motherboard_J_brd_V01_OCP.brd

C51  Q_CAP  10UF 16V 10% X6S  pkg C0805  page 98 : A = P12V_S3_AUX_CPU1_NVDIMM ; B = GND
C2073  Q_CAP_DIFFBUS  DIFF BUS_0.22UF 6.3V 20% X6S  pkg C0201  page 181 : \1\ = P3E_PCH_NVS_TX_DP<1> ; \2\ = P3E_PCH_NVS_TX_C_DP<1>
PR1315  Q_RES  0 5% CHIP  pkg 0402LF  page 296 : A = PVCCD_HV_CPU1_ISYS_R ; B = GND

(kicad_pcb
	(version 20260206)
	(generator "pcbnew")
	(generator_version "10.0")
	(general
		(thickness 1.6)
		(legacy_teardrops no)
	)
	(paper "A4")
	(title_block
		(title "03242023_DA0F0TMBIJ0_F0T_Motherboard_J_brd_V01_OCP.brd")
		(comment 1 "Grand Teton / footprints 4910-4912 of 6105")
	)
	(layers
		(0 "F.Cu" signal "TOP")
		(4 "In1.Cu" signal "GND")
		(6 "In2.Cu" signal "IN1")
		(8 "In3.Cu" signal "GND1")
		(10 "In4.Cu" signal "IN2")
		(12 "In5.Cu" signal "GND2")
		(14 "In6.Cu" signal "IN3")
		(16 "In7.Cu" signal "GND3")
		(18 "In8.Cu" signal "VCC")
		(20 "In9.Cu" signal "VCC1")
		(22 "In10.Cu" signal "GND4")
		(24 "In11.Cu" signal "IN4")
		(26 "In12.Cu" signal "GND5")
		(28 "In13.Cu" signal "IN5")
		(30 "In14.Cu" signal "GND6")
		(32 "In15.Cu" signal "IN6")
		(34 "In16.Cu" signal "GND7")
		(2 "B.Cu" signal "BOTTOM")
		(9 "F.Adhes" user "F.Adhesive")
		(11 "B.Adhes" user "B.Adhesive")
		(13 "F.Paste" user "Package Geometry/Pastemask Top")
		(15 "B.Paste" user "Package Geometry/Pastemask Bottom")
		(5 "F.SilkS" user "Ref Des/Silkscreen Top")
		(7 "B.SilkS" user "Ref Des/Silkscreen Bottom")
		(1 "F.Mask" user "Board Geometry/Soldermask Top")
		(3 "B.Mask" user "Board Geometry/Soldermask Bottom")
		(17 "Dwgs.User" user "User.Drawings")
		(19 "Cmts.User" user "User.Comments")
		(21 "Eco1.User" user "User.Eco1")
		(23 "Eco2.User" user "User.Eco2")
		(25 "Edge.Cuts" user "Board Geometry/Outline")
		(27 "Margin" user)
		(31 "F.CrtYd" user "Package Geometry/Place Bound Top")
		(29 "B.CrtYd" user "Package Geometry/Place Bound Bottom")
		(35 "F.Fab" user "Ref Des/Assembly Top")
		(33 "B.Fab" user "Ref Des/Assembly Bottom")
	)
	(footprint ""
		(layer "B.Cu")
		(at 99.419918 -404.486618 -90)
		(property "Reference" "C2073"
			(at 0 0 90)
			(layer "B.SilkS")
			(hide yes)
			(effects
				(font
					(size 1.27 1.27)
				)
				(justify mirror)
			)
		)
		(property "Value" ""
			(at 0 0 90)
			(layer "B.Fab")
			(effects
				(font
					(size 1.27 1.27)
				)
				(justify mirror)
			)
		)
		(duplicate_pad_numbers_are_jumpers no)
		(fp_line
			(start -0.299974 0.150114)
			(end 0.299974 0.150114)
			(stroke
				(width 0.1)
				(type default)
			)
			(layer "B.Fab")
		)
		(fp_line
			(start 0.299974 0.150114)
			(end 0.299974 -0.150114)
			(stroke
				(width 0.1)
				(type default)
			)
			(layer "B.Fab")
		)
		(fp_line
			(start -0.299974 -0.150114)
			(end -0.299974 0.150114)
			(stroke
				(width 0.1)
				(type default)
			)
			(layer "B.Fab")
		)
		(fp_line
			(start 0.299974 -0.150114)
			(end -0.299974 -0.150114)
			(stroke
				(width 0.1)
				(type default)
			)
			(layer "B.Fab")
		)
		(pad "1" smd rect
			(at 0.2667 0 90)
			(size 0.3048 0.381)
			(layers "B.Cu" "B.Mask" "B.Paste")
			(net "P3E_PCH_NVS_TX_DP<1>")
		)
		(pad "2" smd rect
			(at -0.2667 0 90)
			(size 0.3048 0.381)
			(layers "B.Cu" "B.Mask" "B.Paste")
			(net "P3E_PCH_NVS_TX_C_DP<1>")
		)
		(zone
			(layer "In16.Cu")
			(hatch none 0.5)
			(connect_pads
				(clearance 0)
			)
			(min_thickness 0.25)
			(keepout
				(tracks not_allowed)
				(vias allowed)
				(pads allowed)
				(copperpour not_allowed)
				(footprints allowed)
			)
			(placement
				(enabled no)
				(sheetname "")
			)
			(fill
				(thermal_gap 0.5)
				(thermal_bridge_width 0.5)
				(island_removal_mode 0)
			)
			(polygon
				(pts
					(arc
						(start 99.178618 -404.626318)
						(mid 99.200936 -404.572436)
						(end 99.254818 -404.550118)
					)
					(arc
						(start 99.585018 -404.550118)
						(mid 99.6389 -404.572436)
						(end 99.661218 -404.626318)
					)
					(arc
						(start 99.661218 -404.880318)
						(mid 99.6389 -404.9342)
						(end 99.585018 -404.956518)
					)
					(arc
						(start 99.254818 -404.956518)
						(mid 99.200936 -404.9342)
						(end 99.178618 -404.880318)
					)
				)
			)
		)
		(zone
			(layer "In16.Cu")
			(hatch none 0.5)
			(connect_pads
				(clearance 0)
			)
			(min_thickness 0.25)
			(keepout
				(tracks not_allowed)
				(vias allowed)
				(pads allowed)
				(copperpour not_allowed)
				(footprints allowed)
			)
			(placement
				(enabled no)
				(sheetname "")
			)
			(fill
				(thermal_gap 0.5)
				(thermal_bridge_width 0.5)
				(island_removal_mode 0)
			)
			(polygon
				(pts
					(arc
						(start 99.178618 -404.092918)
						(mid 99.200936 -404.039036)
						(end 99.254818 -404.016718)
					)
					(arc
						(start 99.585018 -404.016718)
						(mid 99.6389 -404.039036)
						(end 99.661218 -404.092918)
					)
					(arc
						(start 99.661218 -404.346918)
						(mid 99.6389 -404.4008)
						(end 99.585018 -404.423118)
					)
					(arc
						(start 99.254818 -404.423118)
						(mid 99.200936 -404.4008)
						(end 99.178618 -404.346918)
					)
				)
			)
		)
	)
	(footprint ""
		(layer "B.Cu")
		(at 57.479946 -321.554856 -90)
		(property "Reference" "C51"
			(at 0 0 90)
			(layer "B.SilkS")
			(hide yes)
			(effects
				(font
					(size 1.27 1.27)
				)
				(justify mirror)
			)
		)
		(property "Value" ""
			(at 0 0 90)
			(layer "B.Fab")
			(effects
				(font
					(size 1.27 1.27)
				)
				(justify mirror)
			)
		)
		(duplicate_pad_numbers_are_jumpers no)
		(fp_line
			(start -1.524 0.762)
			(end 1.524 0.762)
			(stroke
				(width 0.1524)
				(type default)
			)
			(layer "B.SilkS")
		)
		(fp_line
			(start 1.524 0.762)
			(end 1.524 -0.762)
			(stroke
				(width 0.1524)
				(type default)
			)
			(layer "B.SilkS")
		)
		(fp_line
			(start -1.524 -0.762)
			(end -1.524 0.762)
			(stroke
				(width 0.1524)
				(type default)
			)
			(layer "B.SilkS")
		)
		(fp_line
			(start 1.524 -0.762)
			(end -1.524 -0.762)
			(stroke
				(width 0.1524)
				(type default)
			)
			(layer "B.SilkS")
		)
		(fp_line
			(start -1.1049 0.724916)
			(end -1.1049 -0.724916)
			(stroke
				(width 0.1)
				(type default)
			)
			(layer "B.Fab")
		)
		(fp_line
			(start 1.1049 0.724916)
			(end -1.1049 0.724916)
			(stroke
				(width 0.1)
				(type default)
			)
			(layer "B.Fab")
		)
		(fp_line
			(start -1.1049 -0.724916)
			(end 1.1049 -0.724916)
			(stroke
				(width 0.1)
				(type default)
			)
			(layer "B.Fab")
		)
		(fp_line
			(start 1.1049 -0.724916)
			(end 1.1049 0.724916)
			(stroke
				(width 0.1)
				(type default)
			)
			(layer "B.Fab")
		)
		(pad "1" smd rect
			(at 0.889 0 270)
			(size 1.016 1.27)
			(layers "B.Cu" "B.Mask" "B.Paste")
			(net "P12V_S3_AUX_CPU1_NVDIMM")
		)
		(pad "2" smd rect
			(at -0.889 0 270)
			(size 1.016 1.27)
			(layers "B.Cu" "B.Mask" "B.Paste")
			(net "GND")
		)
	)
	(footprint ""
		(layer "B.Cu")
		(at 29.586682 -164.167058)
		(property "Reference" "PR1315"
			(at 0 0 0)
			(layer "B.SilkS")
			(hide yes)
			(effects
				(font
					(size 1.27 1.27)
				)
				(justify mirror)
			)
		)
		(property "Value" ""
			(at 0 0 0)
			(layer "B.Fab")
			(effects
				(font
					(size 1.27 1.27)
				)
				(justify mirror)
			)
		)
		(duplicate_pad_numbers_are_jumpers no)
		(fp_line
			(start -0.7874 -0.4064)
			(end -0.7874 0.4064)
			(stroke
				(width 0.1524)
				(type default)
			)
			(layer "B.SilkS")
		)
		(fp_line
			(start -0.7874 0.4064)
			(end 0.7874 0.4064)
			(stroke
				(width 0.1524)
				(type default)
			)
			(layer "B.SilkS")
		)
		(fp_line
			(start 0.7874 -0.4064)
			(end -0.7874 -0.4064)
			(stroke
				(width 0.1524)
				(type default)
			)
			(layer "B.SilkS")
		)
		(fp_line
			(start 0.7874 0.4064)
			(end 0.7874 -0.4064)
			(stroke
				(width 0.1524)
				(type default)
			)
			(layer "B.SilkS")
		)
		(fp_line
			(start -0.67945 -0.3048)
			(end -0.67945 0.3048)
			(stroke
				(width 0.1)
				(type default)
			)
			(layer "B.Fab")
		)
		(fp_line
			(start -0.67945 0.3048)
			(end -0.120396 0.3048)
			(stroke
				(width 0.1)
				(type default)
			)
			(layer "B.Fab")
		)
		(fp_line
			(start -0.12065 -0.3048)
			(end -0.67945 -0.3048)
			(stroke
				(width 0.1)
				(type default)
			)
			(layer "B.Fab")
		)
		(fp_line
			(start -0.12065 -0.2794)
			(end -0.12065 -0.3048)
			(stroke
				(width 0.1)
				(type default)
			)
			(layer "B.Fab")
		)
		(fp_line
			(start -0.120396 0.2794)
			(end 0.12065 0.2794)
			(stroke
				(width 0.1)
				(type default)
			)
			(layer "B.Fab")
		)
		(fp_line
			(start -0.120396 0.3048)
			(end -0.120396 0.2794)
			(stroke
				(width 0.1)
				(type default)
			)
			(layer "B.Fab")
		)
		(fp_line
			(start 0.12065 -0.305054)
			(end 0.12065 -0.2794)
			(stroke
				(width 0.1)
				(type default)
			)
			(layer "B.Fab")
		)
		(fp_line
			(start 0.12065 -0.2794)
			(end -0.12065 -0.2794)
			(stroke
				(width 0.1)
				(type default)
			)
			(layer "B.Fab")
		)
		(fp_line
			(start 0.12065 0.2794)
			(end 0.12065 0.3048)
			(stroke
				(width 0.1)
				(type default)
			)
			(layer "B.Fab")
		)
		(fp_line
			(start 0.12065 0.3048)
			(end 0.67945 0.3048)
			(stroke
				(width 0.1)
				(type default)
			)
			(layer "B.Fab")
		)
		(fp_line
			(start 0.67945 -0.305054)
			(end 0.12065 -0.305054)
			(stroke
				(width 0.1)
				(type default)
			)
			(layer "B.Fab")
		)
		(fp_line
			(start 0.67945 0.3048)
			(end 0.67945 -0.305054)
			(stroke
				(width 0.1)
				(type default)
			)
			(layer "B.Fab")
		)
		(pad "1" smd circle
			(at 0.40005 0 180)
			(size 0 0)
			(layers "B.Cu" "B.Mask" "B.Paste")
			(net "PVCCD_HV_CPU1_ISYS_R")
		)
		(pad "2" smd circle
			(at -0.40005 0 180)
			(size 0 0)
			(layers "B.Cu" "B.Mask" "B.Paste")
			(net "GND")
		)
	)
)
